(kicad_pcb
	(version 20260206)
	(generator "pcbnew")
	(generator_version "10.0")
	(general
		(thickness 1.6)
		(legacy_teardrops no)
	)
	(paper "A4")
	(title_block
		(title "Bryce Canyon_SCC_16316-1_OCP.brd")
		(comment 1 "Bryce Canyon / footprints 384-390 of 1561")
	)
	(layers
		(0 "F.Cu" signal "TOP")
		(4 "In1.Cu" signal "L2GND")
		(6 "In2.Cu" signal "L3")
		(8 "In3.Cu" signal "L4VCC")
		(10 "In4.Cu" signal "L5VCC")
		(12 "In5.Cu" signal "L6")
		(14 "In6.Cu" signal "L7GND")
		(2 "B.Cu" signal "BOTTOM")
		(9 "F.Adhes" user "F.Adhesive")
		(11 "B.Adhes" user "B.Adhesive")
		(13 "F.Paste" user "Package Geometry/Pastemask Top")
		(15 "B.Paste" user "Package Geometry/Pastemask Bottom")
		(5 "F.SilkS" user "Ref Des/Silkscreen Top")
		(7 "B.SilkS" user "Ref Des/Silkscreen Bottom")
		(1 "F.Mask" user "Board Geometry/Soldermask Top")
		(3 "B.Mask" user "Board Geometry/Soldermask Bottom")
		(17 "Dwgs.User" user "User.Drawings")
		(19 "Cmts.User" user "User.Comments")
		(21 "Eco1.User" user "User.Eco1")
		(23 "Eco2.User" user "User.Eco2")
		(25 "Edge.Cuts" user "Board Geometry/Outline")
		(27 "Margin" user)
		(31 "F.CrtYd" user "Package Geometry/Place Bound Top")
		(29 "B.CrtYd" user "Package Geometry/Place Bound Bottom")
		(35 "F.Fab" user "Ref Des/Assembly Top")
		(33 "B.Fab" user "Ref Des/Assembly Bottom")
	)
	(footprint ""
		(layer "F.Cu")
		(at 73.533 -46.736)
		(property "Reference" "C277"
			(at 0 0 0)
			(layer "F.SilkS")
			(hide yes)
			(effects
				(font
					(size 1.27 1.27)
				)
			)
		)
		(property "Value" "SC100U6D3V6MX-GP"
			(at -0.0762 -5.1308 0)
			(unlocked yes)
			(layer "F.Fab")
			(hide yes)
			(effects
				(font
					(size 1.016 1.016)
					(thickness 0.1524)
				)
			)
		)
		(property "Device Type" "C1206H71"
			(at -0.127 -6.6548 0)
			(unlocked yes)
			(layer "F.Fab")
			(hide yes)
			(effects
				(font
					(size 1.016 1.016)
					(thickness 0.1524)
				)
			)
		)
		(duplicate_pad_numbers_are_jumpers no)
		(fp_line
			(start -1.016 -2.2352)
			(end 1.016 -2.2352)
			(stroke
				(width 0.1524)
				(type default)
			)
			(layer "F.SilkS")
		)
		(fp_line
			(start -1.016 -0.8382)
			(end -1.016 -2.2352)
			(stroke
				(width 0.1524)
				(type default)
			)
			(layer "F.SilkS")
		)
		(fp_line
			(start -1.016 2.2352)
			(end -1.016 0.8382)
			(stroke
				(width 0.1524)
				(type default)
			)
			(layer "F.SilkS")
		)
		(fp_line
			(start 1.016 -2.2352)
			(end 1.016 -0.8382)
			(stroke
				(width 0.1524)
				(type default)
			)
			(layer "F.SilkS")
		)
		(fp_line
			(start 1.016 0.8382)
			(end 1.016 2.2352)
			(stroke
				(width 0.1524)
				(type default)
			)
			(layer "F.SilkS")
		)
		(fp_line
			(start 1.016 2.2352)
			(end -1.016 2.2352)
			(stroke
				(width 0.1524)
				(type default)
			)
			(layer "F.SilkS")
		)
		(fp_rect
			(start -1.0922 2.3114)
			(end 1.0922 -2.3114)
			(stroke
				(width 0)
				(type default)
			)
			(fill no)
			(layer "F.CrtYd")
		)
		(fp_poly
			(pts
				(xy 1.0922 -2.3114) (xy 1.0922 2.3114) (xy -1.0922 2.3114) (xy -1.0922 -2.3114)
			)
			(stroke
				(width 0)
				(type default)
			)
			(fill no)
			(layer "F.Fab")
		)
		(pad "1" smd rect
			(at 0 -1.397)
			(size 1.651 1.27)
			(layers "F.Cu" "F.Mask" "F.Paste")
			(net "GB_VDDA")
		)
		(pad "2" smd rect
			(at 0 1.397)
			(size 1.651 1.27)
			(layers "F.Cu" "F.Mask" "F.Paste")
			(net "GND")
		)
	)
	(footprint ""
		(layer "F.Cu")
		(at 73.533 -57.277)
		(property "Reference" "C290"
			(at 0 0 0)
			(layer "F.SilkS")
			(hide yes)
			(effects
				(font
					(size 1.27 1.27)
				)
			)
		)
		(property "Value" "SC100U6D3V6MX-GP"
			(at -0.0762 -5.1308 0)
			(unlocked yes)
			(layer "F.Fab")
			(hide yes)
			(effects
				(font
					(size 1.016 1.016)
					(thickness 0.1524)
				)
			)
		)
		(property "Device Type" "C1206H71"
			(at -0.127 -6.6548 0)
			(unlocked yes)
			(layer "F.Fab")
			(hide yes)
			(effects
				(font
					(size 1.016 1.016)
					(thickness 0.1524)
				)
			)
		)
		(duplicate_pad_numbers_are_jumpers no)
		(fp_line
			(start -1.016 -2.2352)
			(end 1.016 -2.2352)
			(stroke
				(width 0.1524)
				(type default)
			)
			(layer "F.SilkS")
		)
		(fp_line
			(start -1.016 -0.8382)
			(end -1.016 -2.2352)
			(stroke
				(width 0.1524)
				(type default)
			)
			(layer "F.SilkS")
		)
		(fp_line
			(start -1.016 2.2352)
			(end -1.016 0.8382)
			(stroke
				(width 0.1524)
				(type default)
			)
			(layer "F.SilkS")
		)
		(fp_line
			(start 1.016 -2.2352)
			(end 1.016 -0.8382)
			(stroke
				(width 0.1524)
				(type default)
			)
			(layer "F.SilkS")
		)
		(fp_line
			(start 1.016 0.8382)
			(end 1.016 2.2352)
			(stroke
				(width 0.1524)
				(type default)
			)
			(layer "F.SilkS")
		)
		(fp_line
			(start 1.016 2.2352)
			(end -1.016 2.2352)
			(stroke
				(width 0.1524)
				(type default)
			)
			(layer "F.SilkS")
		)
		(fp_rect
			(start -1.0922 2.3114)
			(end 1.0922 -2.3114)
			(stroke
				(width 0)
				(type default)
			)
			(fill no)
			(layer "F.CrtYd")
		)
		(fp_poly
			(pts
				(xy 1.0922 -2.3114) (xy 1.0922 2.3114) (xy -1.0922 2.3114) (xy -1.0922 -2.3114)
			)
			(stroke
				(width 0)
				(type default)
			)
			(fill no)
			(layer "F.Fab")
		)
		(pad "1" smd rect
			(at 0 -1.397)
			(size 1.651 1.27)
			(layers "F.Cu" "F.Mask" "F.Paste")
			(net "GB_VDDA")
		)
		(pad "2" smd rect
			(at 0 1.397)
			(size 1.651 1.27)
			(layers "F.Cu" "F.Mask" "F.Paste")
			(net "GND")
		)
	)
	(footprint ""
		(layer "F.Cu")
		(at 158.369 -73.34123 -90)
		(property "Reference" "C534"
			(at 0 0 270)
			(layer "F.SilkS")
			(hide yes)
			(effects
				(font
					(size 1.27 1.27)
				)
			)
		)
		(property "Value" "SCD1U16V2KX-3GP"
			(at 1.1811 -2.7051 270)
			(unlocked yes)
			(layer "F.Fab")
			(hide yes)
			(effects
				(font
					(size 1.016 1.016)
					(thickness 0.1524)
				)
			)
		)
		(property "Device Type" "C402H22"
			(at 1.1811 -4.2291 270)
			(unlocked yes)
			(layer "F.Fab")
			(hide yes)
			(effects
				(font
					(size 1.016 1.016)
					(thickness 0.1524)
				)
			)
		)
		(duplicate_pad_numbers_are_jumpers no)
		(fp_rect
			(start -0.4318 0.9525)
			(end 0.4318 -0.9525)
			(stroke
				(width 0)
				(type default)
			)
			(fill no)
			(layer "F.CrtYd")
		)
		(fp_rect
			(start -0.4318 0.9525)
			(end 0.4318 -0.9525)
			(stroke
				(width 0)
				(type default)
			)
			(fill no)
			(layer "F.Fab")
		)
		(pad "1" smd custom
			(at 0 -0.4445 270)
			(size 0.1524 0.1524)
			(layers "F.Cu" "F.Mask" "F.Paste")
			(net "P1V5_C_SENSE")
			(options
				(clearance outline)
				(anchor circle)
			)
			(primitives
				(gr_poly
					(pts
						(arc
							(start 0.3048 -0.2032)
							(mid 0.275042 -0.275042)
							(end 0.2032 -0.3048)
						)
						(arc
							(start -0.2032 -0.3048)
							(mid -0.275042 -0.275042)
							(end -0.3048 -0.2032)
						)
						(arc
							(start -0.3048 0.2032)
							(mid -0.275042 0.275042)
							(end -0.2032 0.3048)
						)
						(arc
							(start 0.2032 0.3048)
							(mid 0.275042 0.275042)
							(end 0.3048 0.2032)
						)
					)
					(width 0)
					(fill yes)
				)
			)
		)
		(pad "2" smd custom
			(at 0 0.4445 270)
			(size 0.1524 0.1524)
			(layers "F.Cu" "F.Mask" "F.Paste")
			(net "GND")
			(options
				(clearance outline)
				(anchor circle)
			)
			(primitives
				(gr_poly
					(pts
						(arc
							(start 0.3048 -0.2032)
							(mid 0.275042 -0.275042)
							(end 0.2032 -0.3048)
						)
						(arc
							(start -0.2032 -0.3048)
							(mid -0.275042 -0.275042)
							(end -0.3048 -0.2032)
						)
						(arc
							(start -0.3048 0.2032)
							(mid -0.275042 0.275042)
							(end -0.2032 0.3048)
						)
						(arc
							(start 0.2032 0.3048)
							(mid 0.275042 0.275042)
							(end 0.3048 0.2032)
						)
					)
					(width 0)
					(fill yes)
				)
			)
		)
	)
	(footprint ""
		(layer "F.Cu")
		(at 82.825082 -104.359964 180)
		(property "Reference" "R553"
			(at 0 0 180)
			(layer "F.SilkS")
			(hide yes)
			(effects
				(font
					(size 1.27 1.27)
				)
			)
		)
		(property "Value" "0R2J-2-GP"
			(at 0.064008 -3.993896 180)
			(unlocked yes)
			(layer "F.Fab")
			(hide yes)
			(effects
				(font
					(size 1.016 1.016)
					(thickness 0.1524)
				)
			)
		)
		(property "Device Type" "R402H16"
			(at 0.064008 -5.517896 180)
			(unlocked yes)
			(layer "F.Fab")
			(hide yes)
			(effects
				(font
					(size 1.016 1.016)
					(thickness 0.1524)
				)
			)
		)
		(duplicate_pad_numbers_are_jumpers no)
		(fp_line
			(start 0.508 -0.9398)
			(end -0.508 -0.9398)
			(stroke
				(width 0.1524)
				(type default)
			)
			(layer "F.SilkS")
		)
		(fp_line
			(start -0.508 -0.9398)
			(end -0.508 0.9398)
			(stroke
				(width 0.1524)
				(type default)
			)
			(layer "F.SilkS")
		)
		(fp_rect
			(start -0.508 0.9398)
			(end 0.508 -0.9398)
			(stroke
				(width 0)
				(type default)
			)
			(fill no)
			(layer "F.CrtYd")
		)
		(fp_rect
			(start -0.508 0.9398)
			(end 0.508 -0.9398)
			(stroke
				(width 0)
				(type default)
			)
			(fill no)
			(layer "F.Fab")
		)
		(pad "1" smd custom
			(at 0 -0.4445 180)
			(size 0.1397 0.1397)
			(layers "F.Cu" "F.Mask" "F.Paste")
			(net "SCC_FULL_PWR_BUF_EN")
			(options
				(clearance outline)
				(anchor circle)
			)
			(primitives
				(gr_poly
					(pts
						(arc
							(start -0.1778 -0.2794)
							(mid -0.249642 -0.249642)
							(end -0.2794 -0.1778)
						)
						(arc
							(start -0.2794 0.1778)
							(mid -0.249642 0.249642)
							(end -0.1778 0.2794)
						)
						(arc
							(start 0.1778 0.2794)
							(mid 0.249642 0.249642)
							(end 0.2794 0.1778)
						)
						(arc
							(start 0.2794 -0.1778)
							(mid 0.249642 -0.249642)
							(end 0.1778 -0.2794)
						)
					)
					(width 0)
					(fill yes)
				)
			)
		)
		(pad "2" smd custom
			(at 0 0.4445 180)
			(size 0.1397 0.1397)
			(layers "F.Cu" "F.Mask" "F.Paste")
			(net "SCC_FULL_PWR_BUF_EN_U48")
			(options
				(clearance outline)
				(anchor circle)
			)
			(primitives
				(gr_poly
					(pts
						(arc
							(start -0.1778 -0.2794)
							(mid -0.249642 -0.249642)
							(end -0.2794 -0.1778)
						)
						(arc
							(start -0.2794 0.1778)
							(mid -0.249642 0.249642)
							(end -0.1778 0.2794)
						)
						(arc
							(start 0.1778 0.2794)
							(mid 0.249642 0.249642)
							(end 0.2794 0.1778)
						)
						(arc
							(start 0.2794 -0.1778)
							(mid 0.249642 -0.249642)
							(end 0.1778 -0.2794)
						)
					)
					(width 0)
					(fill yes)
				)
			)
		)
	)
	(footprint ""
		(layer "F.Cu")
		(at 170.171618 -100.629974 -90)
		(property "Reference" "C625"
			(at 0 0 270)
			(layer "F.SilkS")
			(hide yes)
			(effects
				(font
					(size 1.27 1.27)
				)
			)
		)
		(property "Value" "SC1KP50V2KX-1GP"
			(at 1.1811 -2.7051 270)
			(unlocked yes)
			(layer "F.Fab")
			(hide yes)
			(effects
				(font
					(size 1.016 1.016)
					(thickness 0.1524)
				)
			)
		)
		(property "Device Type" "C402H22"
			(at 1.1811 -4.2291 270)
			(unlocked yes)
			(layer "F.Fab")
			(hide yes)
			(effects
				(font
					(size 1.016 1.016)
					(thickness 0.1524)
				)
			)
		)
		(duplicate_pad_numbers_are_jumpers no)
		(fp_rect
			(start -0.4318 0.9525)
			(end 0.4318 -0.9525)
			(stroke
				(width 0)
				(type default)
			)
			(fill no)
			(layer "F.CrtYd")
		)
		(fp_rect
			(start -0.4318 0.9525)
			(end 0.4318 -0.9525)
			(stroke
				(width 0)
				(type default)
			)
			(fill no)
			(layer "F.Fab")
		)
		(pad "1" smd custom
			(at 0 -0.4445 270)
			(size 0.1524 0.1524)
			(layers "F.Cu" "F.Mask" "F.Paste")
			(net "VT235_VREF")
			(options
				(clearance outline)
				(anchor circle)
			)
			(primitives
				(gr_poly
					(pts
						(arc
							(start 0.3048 -0.2032)
							(mid 0.275042 -0.275042)
							(end 0.2032 -0.3048)
						)
						(arc
							(start -0.2032 -0.3048)
							(mid -0.275042 -0.275042)
							(end -0.3048 -0.2032)
						)
						(arc
							(start -0.3048 0.2032)
							(mid -0.275042 0.275042)
							(end -0.2032 0.3048)
						)
						(arc
							(start 0.2032 0.3048)
							(mid 0.275042 0.275042)
							(end 0.3048 0.2032)
						)
					)
					(width 0)
					(fill yes)
				)
			)
		)
		(pad "2" smd custom
			(at 0 0.4445 270)
			(size 0.1524 0.1524)
			(layers "F.Cu" "F.Mask" "F.Paste")
			(net "VT235_VDES_RCC")
			(options
				(clearance outline)
				(anchor circle)
			)
			(primitives
				(gr_poly
					(pts
						(arc
							(start 0.3048 -0.2032)
							(mid 0.275042 -0.275042)
							(end 0.2032 -0.3048)
						)
						(arc
							(start -0.2032 -0.3048)
							(mid -0.275042 -0.275042)
							(end -0.3048 -0.2032)
						)
						(arc
							(start -0.3048 0.2032)
							(mid -0.275042 0.275042)
							(end -0.2032 0.3048)
						)
						(arc
							(start 0.2032 0.3048)
							(mid 0.275042 0.275042)
							(end 0.3048 0.2032)
						)
					)
					(width 0)
					(fill yes)
				)
			)
		)
	)
	(footprint ""
		(layer "F.Cu")
		(at 136.248902 -75.35672 90)
		(property "Reference" "C682"
			(at 0 0 90)
			(layer "F.SilkS")
			(hide yes)
			(effects
				(font
					(size 1.27 1.27)
				)
			)
		)
		(property "Value" "SCD01U16V1KX-GP"
			(at -2.8321 -1.7399 90)
			(unlocked yes)
			(layer "F.Fab")
			(hide yes)
			(effects
				(font
					(size 1.016 1.016)
					(thickness 0.1524)
				)
			)
		)
		(property "Device Type" "C0201H13"
			(at -2.8321 -3.2639 90)
			(unlocked yes)
			(layer "F.Fab")
			(hide yes)
			(effects
				(font
					(size 1.016 1.016)
					(thickness 0.1524)
				)
			)
		)
		(duplicate_pad_numbers_are_jumpers no)
		(fp_rect
			(start -0.2794 0.6477)
			(end 0.2794 -0.6477)
			(stroke
				(width 0)
				(type default)
			)
			(fill no)
			(layer "F.CrtYd")
		)
		(fp_rect
			(start -0.2794 0.6477)
			(end 0.2794 -0.6477)
			(stroke
				(width 0)
				(type default)
			)
			(fill no)
			(layer "F.Fab")
		)
		(pad "1" smd custom
			(at 0 -0.2794 90)
			(size 0.0762 0.0762)
			(layers "F.Cu" "F.Mask" "F.Paste")
			(net "PHY_EXP_TO_CONN_C_8_DP")
			(options
				(clearance outline)
				(anchor circle)
			)
			(primitives
				(gr_poly
					(pts
						(arc
							(start 0.1524 -0.127)
							(mid 0.137521 -0.162921)
							(end 0.1016 -0.1778)
						)
						(arc
							(start -0.1016 -0.1778)
							(mid -0.137521 -0.162921)
							(end -0.1524 -0.127)
						)
						(arc
							(start -0.1524 0.127)
							(mid -0.137521 0.162921)
							(end -0.1016 0.1778)
						)
						(arc
							(start 0.1016 0.1778)
							(mid 0.137521 0.162921)
							(end 0.1524 0.127)
						)
					)
					(width 0)
					(fill yes)
				)
			)
		)
		(pad "2" smd custom
			(at 0 0.2794 90)
			(size 0.0762 0.0762)
			(layers "F.Cu" "F.Mask" "F.Paste")
			(net "PHY_EXP_TO_CONN_8_DP")
			(options
				(clearance outline)
				(anchor circle)
			)
			(primitives
				(gr_poly
					(pts
						(arc
							(start 0.1524 -0.127)
							(mid 0.137521 -0.162921)
							(end 0.1016 -0.1778)
						)
						(arc
							(start -0.1016 -0.1778)
							(mid -0.137521 -0.162921)
							(end -0.1524 -0.127)
						)
						(arc
							(start -0.1524 0.127)
							(mid -0.137521 0.162921)
							(end -0.1016 0.1778)
						)
						(arc
							(start 0.1016 0.1778)
							(mid 0.137521 0.162921)
							(end 0.1524 0.127)
						)
					)
					(width 0)
					(fill yes)
				)
			)
		)
	)
	(footprint ""
		(layer "F.Cu")
		(at 68.274438 -77.560424 180)
		(property "Reference" "U39"
			(at 0 0 180)
			(layer "F.SilkS")
			(hide yes)
			(effects
				(font
					(size 1.27 1.27)
				)
			)
		)
		(property "Value" "PCA9306DCTR-GP"
			(at 0 -11.6332 180)
			(unlocked yes)
			(layer "F.Fab")
			(hide yes)
			(effects
				(font
					(size 1.016 1.016)
					(thickness 0.1524)
				)
			)
		)
		(property "Device Type" "SSOIC8H52"
			(at 0 -13.1572 180)
			(unlocked yes)
			(layer "F.Fab")
			(hide yes)
			(effects
				(font
					(size 1.016 1.016)
					(thickness 0.1524)
				)
			)
		)
		(duplicate_pad_numbers_are_jumpers no)
		(fp_line
			(start 1.0668 0.5842)
			(end -1.524 0.5842)
			(stroke
				(width 0.1524)
				(type default)
			)
			(layer "F.SilkS")
		)
		(fp_line
			(start 1.0668 -0.5842)
			(end 1.0668 0.5842)
			(stroke
				(width 0.1524)
				(type default)
			)
			(layer "F.SilkS")
		)
		(fp_line
			(start -1.397 0)
			(end -1.7018 0.3048)
			(stroke
				(width 0.1524)
				(type default)
			)
			(layer "F.SilkS")
		)
		(fp_line
			(start -1.397 0)
			(end -1.7018 -0.3048)
			(stroke
				(width 0.1524)
				(type default)
			)
			(layer "F.SilkS")
		)
		(fp_line
			(start -1.524 0.5842)
			(end -1.524 2.286)
			(stroke
				(width 0.508)
				(type default)
			)
			(layer "F.SilkS")
		)
		(fp_line
			(start -1.7018 -0.5842)
			(end 1.0668 -0.5842)
			(stroke
				(width 0.1524)
				(type default)
			)
			(layer "F.SilkS")
		)
		(fp_line
			(start -1.7018 -0.5842)
			(end -1.7018 2.286)
			(stroke
				(width 0.1524)
				(type default)
			)
			(layer "F.SilkS")
		)
		(fp_poly
			(pts
				(xy -1.1684 -0.5842) (xy 1.0668 -0.5842) (xy 1.0668 0.5842) (xy -1.1684 0.5842)
			)
			(stroke
				(width 0)
				(type default)
			)
			(fill yes)
			(layer "F.SilkS")
		)
		(fp_poly
			(pts
				(xy -1.778 2.54) (xy 1.778 2.54) (xy 1.778 -2.54) (xy -1.778 -2.54)
			)
			(stroke
				(width 0)
				(type default)
			)
			(fill no)
			(layer "F.CrtYd")
		)
		(fp_poly
			(pts
				(xy -1.778 -2.54) (xy 1.778 -2.54) (xy 1.778 2.54) (xy -1.778 2.54)
			)
			(stroke
				(width 0)
				(type default)
			)
			(fill no)
			(layer "F.Fab")
		)
		(pad "1" smd rect
			(at -0.97536 1.6256 180)
			(size 0.3556 1.524)
			(layers "F.Cu" "F.Mask" "F.Paste")
			(net "GND")
		)
		(pad "2" smd rect
			(at -0.32512 1.6256 180)
			(size 0.3556 1.524)
			(layers "F.Cu" "F.Mask" "F.Paste")
			(net "P1V8_E")
		)
		(pad "3" smd rect
			(at 0.32512 1.6256 180)
			(size 0.3556 1.524)
			(layers "F.Cu" "F.Mask" "F.Paste")
			(net "I2C_DRIVE_FLT_LED_SCL6_LS")
		)
		(pad "4" smd rect
			(at 0.97536 1.6256 180)
			(size 0.3556 1.524)
			(layers "F.Cu" "F.Mask" "F.Paste")
			(net "I2C_DRIVE_FLT_LED_SDA6_LS")
		)
		(pad "5" smd rect
			(at 0.97536 -1.6256 180)
			(size 0.3556 1.524)
			(layers "F.Cu" "F.Mask" "F.Paste")
			(net "I2C_DRIVE_FLT_LED_SDA6")
		)
		(pad "6" smd rect
			(at 0.32512 -1.6256 180)
			(size 0.3556 1.524)
			(layers "F.Cu" "F.Mask" "F.Paste")
			(net "I2C_DRIVE_FLT_LED_SCL6")
		)
		(pad "7" smd rect
			(at -0.32512 -1.6256 180)
			(size 0.3556 1.524)
			(layers "F.Cu" "F.Mask" "F.Paste")
			(net "VREF6")
		)
		(pad "8" smd rect
			(at -0.97536 -1.6256 180)
			(size 0.3556 1.524)
			(layers "F.Cu" "F.Mask" "F.Paste")
			(net "LS_EN_U39")
		)
	)
)
